# BASEBOARD_FAB2 (Tioga Pass) — schematic netlist excerpt (pin names and nets, part order shuffled) for the footprints in the layout excerpt that follows; sources: Cadence DE-HDL packaged netlist, KiCad conversion of Wiwynn_Tioga_Pass_MB.brd

C7A14  SC22U16V5MX-4-GP  20%  pkg SMD-BCG5  page 236 : \1\ = VR_FET_SW_P12V_STBY_PVDDQ_DEF ; \2\ = GND
R25W52  120R2F-GP  1%  pkg RCL_GP  page 151 : \1\ = BMC_M_MACT_N ; \2\ = P1V2_AUX_BMC
C6A7  CAP  10UF 4V 20% X6S  pkg 0603LF  page 232 : A = PVPP_DEF ; B = GND

(kicad_pcb
	(version 20260206)
	(generator "pcbnew")
	(generator_version "10.0")
	(general
		(thickness 1.6)
		(legacy_teardrops no)
	)
	(paper "A4")
	(title_block
		(title "Wiwynn_Tioga_Pass_MB.brd")
		(comment 1 "Tioga Pass / footprints 1505-1507 of 4770")
	)
	(layers
		(0 "F.Cu" signal "TOP")
		(4 "In1.Cu" signal "L2GND")
		(6 "In2.Cu" signal "L3")
		(8 "In3.Cu" signal "L4GND")
		(10 "In4.Cu" signal "L5")
		(12 "In5.Cu" signal "L6GND")
		(14 "In6.Cu" signal "L7VCC")
		(16 "In7.Cu" signal "L8VCC")
		(18 "In8.Cu" signal "L9GND")
		(20 "In9.Cu" signal "L10")
		(22 "In10.Cu" signal "L11GND")
		(24 "In11.Cu" signal "L12")
		(26 "In12.Cu" signal "L13GND")
		(2 "B.Cu" signal "BOTTOM")
		(9 "F.Adhes" user "F.Adhesive")
		(11 "B.Adhes" user "B.Adhesive")
		(13 "F.Paste" user "Package Geometry/Pastemask Top")
		(15 "B.Paste" user "Package Geometry/Pastemask Bottom")
		(5 "F.SilkS" user "Ref Des/Silkscreen Top")
		(7 "B.SilkS" user "Ref Des/Silkscreen Bottom")
		(1 "F.Mask" user "Board Geometry/Soldermask Top")
		(3 "B.Mask" user "Board Geometry/Soldermask Bottom")
		(17 "Dwgs.User" user "User.Drawings")
		(19 "Cmts.User" user "User.Comments")
		(21 "Eco1.User" user "User.Eco1")
		(23 "Eco2.User" user "User.Eco2")
		(25 "Edge.Cuts" user "Board Geometry/Outline")
		(27 "Margin" user)
		(31 "F.CrtYd" user "Package Geometry/Place Bound Top")
		(29 "B.CrtYd" user "Package Geometry/Place Bound Bottom")
		(35 "F.Fab" user "Ref Des/Assembly Top")
		(33 "B.Fab" user "Ref Des/Assembly Bottom")
	)
	(footprint ""
		(layer "F.Cu")
		(at 451.85838 -32.4485 90)
		(property "Reference" "R25W52"
			(at 0 0 90)
			(layer "F.SilkS")
			(hide yes)
			(effects
				(font
					(size 1.27 1.27)
				)
			)
		)
		(property "Value" "*"
			(at 0.064008 -4.108196 90)
			(unlocked yes)
			(layer "F.Fab")
			(hide yes)
			(effects
				(font
					(size 1.27 1.016)
					(thickness 0.1524)
				)
			)
		)
		(property "Device Type" "120R2F-GP_RCL_GP-120R2F-GP,64.A"
			(at 0.064008 -5.632196 90)
			(unlocked yes)
			(layer "F.Fab")
			(hide yes)
			(effects
				(font
					(size 1.27 1.016)
					(thickness 0.1524)
				)
			)
		)
		(duplicate_pad_numbers_are_jumpers no)
		(fp_line
			(start 0.508 -0.9398)
			(end -0.508 -0.9398)
			(stroke
				(width 0.1524)
				(type default)
			)
			(layer "F.SilkS")
		)
		(fp_line
			(start -0.508 -0.9398)
			(end -0.508 0.9398)
			(stroke
				(width 0.1524)
				(type default)
			)
			(layer "F.SilkS")
		)
		(fp_rect
			(start -0.508 0.9398)
			(end 0.508 -0.9398)
			(stroke
				(width 0)
				(type default)
			)
			(fill no)
			(layer "F.CrtYd")
		)
		(fp_rect
			(start -0.508 0.9398)
			(end 0.508 -0.9398)
			(stroke
				(width 0)
				(type default)
			)
			(fill no)
			(layer "F.Fab")
		)
		(pad "1" smd custom
			(at 0 -0.4445 90)
			(size 0.1397 0.1397)
			(layers "F.Cu" "F.Mask" "F.Paste")
			(net "BMC_M_MACT_N")
			(options
				(clearance outline)
				(anchor circle)
			)
			(primitives
				(gr_poly
					(pts
						(arc
							(start -0.1778 -0.2794)
							(mid -0.249642 -0.249642)
							(end -0.2794 -0.1778)
						)
						(arc
							(start -0.2794 0.1778)
							(mid -0.249642 0.249642)
							(end -0.1778 0.2794)
						)
						(arc
							(start 0.1778 0.2794)
							(mid 0.249642 0.249642)
							(end 0.2794 0.1778)
						)
						(arc
							(start 0.2794 -0.1778)
							(mid 0.249642 -0.249642)
							(end 0.1778 -0.2794)
						)
					)
					(width 0)
					(fill yes)
				)
			)
		)
		(pad "2" smd custom
			(at 0 0.4445 90)
			(size 0.1397 0.1397)
			(layers "F.Cu" "F.Mask" "F.Paste")
			(net "P1V2_AUX_BMC")
			(options
				(clearance outline)
				(anchor circle)
			)
			(primitives
				(gr_poly
					(pts
						(arc
							(start -0.1778 -0.2794)
							(mid -0.249642 -0.249642)
							(end -0.2794 -0.1778)
						)
						(arc
							(start -0.2794 0.1778)
							(mid -0.249642 0.249642)
							(end -0.1778 0.2794)
						)
						(arc
							(start 0.1778 0.2794)
							(mid 0.249642 0.249642)
							(end 0.2794 0.1778)
						)
						(arc
							(start 0.2794 -0.1778)
							(mid 0.249642 -0.249642)
							(end 0.1778 -0.2794)
						)
					)
					(width 0)
					(fill yes)
				)
			)
		)
	)
	(footprint ""
		(layer "F.Cu")
		(at 369.954556 -156.250894 180)
		(property "Reference" "C7A14"
			(at 0 0 180)
			(layer "F.SilkS")
			(hide yes)
			(effects
				(font
					(size 1.27 1.27)
				)
			)
		)
		(property "Value" "*"
			(at -0.0762 -6.2357 180)
			(unlocked yes)
			(layer "F.Fab")
			(hide yes)
			(effects
				(font
					(size 1.27 1.016)
					(thickness 0.1524)
				)
			)
		)
		(property "Device Type" "SC22U16V5MX-4-GP_SMD-BCG5-SC22A"
			(at -0.0762 -8.2677 180)
			(unlocked yes)
			(layer "F.Fab")
			(hide yes)
			(effects
				(font
					(size 1.27 1.016)
					(thickness 0.1524)
				)
			)
		)
		(duplicate_pad_numbers_are_jumpers no)
		(fp_line
			(start 0.635 0)
			(end -0.635 0)
			(stroke
				(width 0.508)
				(type default)
			)
			(layer "F.SilkS")
		)
		(fp_rect
			(start -0.9652 1.778)
			(end 0.9652 -1.778)
			(stroke
				(width 0)
				(type default)
			)
			(fill no)
			(layer "F.CrtYd")
		)
		(fp_poly
			(pts
				(xy -0.9652 -1.778) (xy 0.9652 -1.778) (xy 0.9652 1.778) (xy -0.9652 1.778)
			)
			(stroke
				(width 0)
				(type default)
			)
			(fill no)
			(layer "F.Fab")
		)
		(pad "1" smd rect
			(at 0 -0.9652 180)
			(size 1.397 1.143)
			(layers "F.Cu" "F.Mask" "F.Paste")
			(net "VR_FET_SW_P12V_STBY_PVDDQ_DEF")
		)
		(pad "2" smd rect
			(at 0 0.9652 180)
			(size 1.397 1.143)
			(layers "F.Cu" "F.Mask" "F.Paste")
			(net "GND")
		)
	)
	(footprint ""
		(layer "F.Cu")
		(at 320.296032 -140.208 90)
		(property "Reference" "C6A7"
			(at 0 0 90)
			(layer "F.SilkS")
			(hide yes)
			(effects
				(font
					(size 1.27 1.27)
				)
			)
		)
		(property "Value" ""
			(at 0 0 90)
			(layer "F.Fab")
			(effects
				(font
					(size 1.27 1.27)
				)
			)
		)
		(duplicate_pad_numbers_are_jumpers no)
		(fp_poly
			(pts
				(xy -0.4953 -0.2032) (xy 0.4953 -0.2032) (xy 0.4953 1.6002) (xy -0.4953 1.6002)
			)
			(stroke
				(width 0)
				(type default)
			)
			(fill no)
			(layer "F.CrtYd")
		)
		(fp_line
			(start 0.4953 -0.2032)
			(end 0.4953 1.6002)
			(stroke
				(width 0.1)
				(type default)
			)
			(layer "F.Fab")
		)
		(fp_line
			(start -0.4953 -0.2032)
			(end 0.4953 -0.2032)
			(stroke
				(width 0.1)
				(type default)
			)
			(layer "F.Fab")
		)
		(fp_line
			(start 0.4953 1.6002)
			(end -0.4953 1.6002)
			(stroke
				(width 0.1)
				(type default)
			)
			(layer "F.Fab")
		)
		(fp_line
			(start -0.4953 1.6002)
			(end -0.4953 -0.2032)
			(stroke
				(width 0.1)
				(type default)
			)
			(layer "F.Fab")
		)
		(pad "1" smd rect
			(at 0 0 90)
			(size 0.762 0.889)
			(layers "F.Cu" "F.Mask" "F.Paste")
			(net "PVPP_DEF")
		)
		(pad "2" smd rect
			(at 0 1.397 90)
			(size 0.762 0.889)
			(layers "F.Cu" "F.Mask" "F.Paste")
			(net "GND")
		)
		(zone
			(layer "F.Cu")
			(hatch none 0.5)
			(connect_pads
				(clearance 0)
			)
			(min_thickness 0.25)
			(keepout
				(tracks not_allowed)
				(vias allowed)
				(pads allowed)
				(copperpour not_allowed)
				(footprints allowed)
			)
			(placement
				(enabled no)
				(sheetname "")
			)
			(fill
				(thermal_gap 0.5)
				(thermal_bridge_width 0.5)
				(island_removal_mode 0)
			)
			(polygon
				(pts
					(xy 320.740532 -139.827) (xy 320.740532 -140.589) (xy 321.248532 -140.589) (xy 321.248532 -139.827)
				)
			)
		)
	)
)
